(kicad_pcb
	(version 20260206)
	(generator "pcbnew")
	(generator_version "10.0")
	(general
		(thickness 1.6)
		(legacy_teardrops no)
	)
	(paper "A4")
	(title_block
		(title "fcb — 12433-1M.1206WZS1330.brd")
		(comment 1 "Open Vault / Knox (Wiwynn) / footprints 66-71 of 495")
	)
	(layers
		(0 "F.Cu" signal "TOP")
		(4 "In1.Cu" signal "L2GND")
		(6 "In2.Cu" signal "L3VCC")
		(2 "B.Cu" signal "BOTTOM")
		(9 "F.Adhes" user "F.Adhesive")
		(11 "B.Adhes" user "B.Adhesive")
		(13 "F.Paste" user "Package Geometry/Pastemask Top")
		(15 "B.Paste" user "Package Geometry/Pastemask Bottom")
		(5 "F.SilkS" user "Ref Des/Silkscreen Top")
		(7 "B.SilkS" user "Ref Des/Silkscreen Bottom")
		(1 "F.Mask" user "Board Geometry/Soldermask Top")
		(3 "B.Mask" user "Board Geometry/Soldermask Bottom")
		(17 "Dwgs.User" user "User.Drawings")
		(19 "Cmts.User" user "User.Comments")
		(21 "Eco1.User" user "User.Eco1")
		(23 "Eco2.User" user "User.Eco2")
		(25 "Edge.Cuts" user "Board Geometry/Outline")
		(27 "Margin" user)
		(31 "F.CrtYd" user "Package Geometry/Place Bound Top")
		(29 "B.CrtYd" user "Package Geometry/Place Bound Bottom")
		(35 "F.Fab" user "Ref Des/Assembly Top")
		(33 "B.Fab" user "Ref Des/Assembly Bottom")
	)
	(footprint ""
		(layer "F.Cu")
		(at 22.479 -181.7116 90)
		(property "Reference" "D8"
			(at 0 0 90)
			(layer "F.SilkS")
			(hide yes)
			(effects
				(font
					(size 1.27 1.27)
				)
			)
		)
		(property "Value" "BAS16H-GP"
			(at 0 -5.5372 90)
			(unlocked yes)
			(layer "F.Fab")
			(hide yes)
			(effects
				(font
					(size 1.016 1.016)
					(thickness 0.1524)
				)
			)
		)
		(property "Device Type" "SOD123AKH48"
			(at 0 -7.0612 90)
			(unlocked yes)
			(layer "F.Fab")
			(hide yes)
			(effects
				(font
					(size 1.016 1.016)
					(thickness 0.1524)
				)
			)
		)
		(duplicate_pad_numbers_are_jumpers no)
		(fp_line
			(start 1.016 -2.667)
			(end -1.016 -2.667)
			(stroke
				(width 0.1524)
				(type default)
			)
			(layer "F.SilkS")
		)
		(fp_line
			(start -1.016 -2.667)
			(end -1.016 2.667)
			(stroke
				(width 0.1524)
				(type default)
			)
			(layer "F.SilkS")
		)
		(fp_line
			(start 1.016 2.667)
			(end 1.016 -2.667)
			(stroke
				(width 0.1524)
				(type default)
			)
			(layer "F.SilkS")
		)
		(fp_line
			(start -1.016 2.667)
			(end 1.016 2.667)
			(stroke
				(width 0.1524)
				(type default)
			)
			(layer "F.SilkS")
		)
		(fp_line
			(start 0.889 2.921)
			(end -0.889 2.921)
			(stroke
				(width 0.508)
				(type default)
			)
			(layer "F.SilkS")
		)
		(fp_rect
			(start -1.143 3.175)
			(end 1.143 -2.794)
			(stroke
				(width 0)
				(type default)
			)
			(fill no)
			(layer "F.CrtYd")
		)
		(fp_poly
			(pts
				(xy -1.143 -2.794) (xy 1.143 -2.794) (xy 1.143 3.175) (xy -1.143 3.175)
			)
			(stroke
				(width 0)
				(type default)
			)
			(fill no)
			(layer "F.Fab")
		)
		(pad "A" smd rect
			(at 0 -1.6891 90)
			(size 0.889 1.397)
			(layers "F.Cu" "F.Mask" "F.Paste")
			(net "FAN_TACH7")
		)
		(pad "K" smd rect
			(at 0 1.6891 90)
			(size 0.889 1.397)
			(layers "F.Cu" "F.Mask" "F.Paste")
			(net "P12V")
		)
	)
	(footprint ""
		(layer "F.Cu")
		(at 37.032692 -289.281362 180)
		(property "Reference" "TC17"
			(at 0 0 180)
			(layer "F.SilkS")
			(hide yes)
			(effects
				(font
					(size 1.27 1.27)
				)
			)
		)
		(property "Value" "ST15U25VDM-1-GP"
			(at 0 -9.6012 180)
			(unlocked yes)
			(layer "F.Fab")
			(hide yes)
			(effects
				(font
					(size 1.016 1.016)
					(thickness 0.1524)
				)
			)
		)
		(property "Device Type" "CT7343H79"
			(at 0 -11.1252 180)
			(unlocked yes)
			(layer "F.Fab")
			(hide yes)
			(effects
				(font
					(size 1.016 1.016)
					(thickness 0.1524)
				)
			)
		)
		(duplicate_pad_numbers_are_jumpers no)
		(fp_line
			(start 2.286 4.8768)
			(end -2.286 4.8768)
			(stroke
				(width 0.1524)
				(type default)
			)
			(layer "F.SilkS")
		)
		(fp_line
			(start 2.286 2.032)
			(end 2.286 4.8768)
			(stroke
				(width 0.1524)
				(type default)
			)
			(layer "F.SilkS")
		)
		(fp_line
			(start 2.286 -2.032)
			(end 2.286 -4.8768)
			(stroke
				(width 0.1524)
				(type default)
			)
			(layer "F.SilkS")
		)
		(fp_line
			(start 2.286 -4.8768)
			(end -2.286 -4.8768)
			(stroke
				(width 0.1524)
				(type default)
			)
			(layer "F.SilkS")
		)
		(fp_line
			(start 2.1082 -4.699)
			(end -2.1082 -4.699)
			(stroke
				(width 0.508)
				(type default)
			)
			(layer "F.SilkS")
		)
		(fp_line
			(start -2.286 4.8768)
			(end -2.286 2.032)
			(stroke
				(width 0.1524)
				(type default)
			)
			(layer "F.SilkS")
		)
		(fp_line
			(start -2.286 -4.8768)
			(end -2.286 -2.032)
			(stroke
				(width 0.1524)
				(type default)
			)
			(layer "F.SilkS")
		)
		(fp_rect
			(start -2.1463 3.6449)
			(end 2.1463 -3.6449)
			(stroke
				(width 0)
				(type default)
			)
			(fill no)
			(layer "F.CrtYd")
		)
		(fp_poly
			(pts
				(xy -2.54 4.953) (xy -2.54 4.2926) (xy -3.81 4.2926) (xy -3.81 -4.2926) (xy -2.54 -4.2926) (xy -2.54 -4.953)
				(xy 2.54 -4.953) (xy 2.54 -4.2926) (xy 3.81 -4.2926) (xy 3.81 -1.6256) (xy 2.1463 -1.6256) (xy 2.1463 -3.6449)
				(xy -2.1463 -3.6449) (xy -2.1463 3.6449) (xy 2.1463 3.6449) (xy 2.1463 -1.6129) (xy 3.81 -1.6129)
				(xy 3.81 4.2926) (xy 2.54 4.2926) (xy 2.54 4.953)
			)
			(stroke
				(width 0)
				(type default)
			)
			(fill no)
			(layer "F.CrtYd")
		)
		(fp_rect
			(start 2.54 4.2926)
			(end 3.81 -4.2926)
			(stroke
				(width 0)
				(type default)
			)
			(fill no)
			(layer "F.Fab")
		)
		(fp_rect
			(start -2.54 4.953)
			(end 2.54 -4.953)
			(stroke
				(width 0)
				(type default)
			)
			(fill no)
			(layer "F.Fab")
		)
		(fp_rect
			(start -3.81 4.2926)
			(end -2.54 -4.2926)
			(stroke
				(width 0)
				(type default)
			)
			(fill no)
			(layer "F.Fab")
		)
		(pad "1" smd rect
			(at 0 -3.1496 180)
			(size 2.413 2.286)
			(layers "F.Cu" "F.Mask" "F.Paste")
			(net "P12V")
		)
		(pad "2" smd rect
			(at 0 3.1496 180)
			(size 2.413 2.286)
			(layers "F.Cu" "F.Mask" "F.Paste")
			(net "GND")
		)
		(zone
			(layer "F.Cu")
			(hatch none 0.5)
			(connect_pads
				(clearance 0)
			)
			(min_thickness 0.25)
			(keepout
				(tracks allowed)
				(vias not_allowed)
				(pads allowed)
				(copperpour not_allowed)
				(footprints allowed)
			)
			(placement
				(enabled no)
				(sheetname "")
			)
			(fill
				(thermal_gap 0.5)
				(thermal_bridge_width 0.5)
				(island_removal_mode 0)
			)
			(polygon
				(pts
					(xy 35.521392 -287.592262) (xy 35.521392 -284.683962) (xy 38.543992 -284.683962) (xy 38.543992 -287.579562)
					(xy 38.543992 -287.909762) (xy 35.521392 -287.909762)
				)
			)
		)
		(zone
			(layer "F.Cu")
			(hatch none 0.5)
			(connect_pads
				(clearance 0)
			)
			(min_thickness 0.25)
			(keepout
				(tracks allowed)
				(vias not_allowed)
				(pads allowed)
				(copperpour not_allowed)
				(footprints allowed)
			)
			(placement
				(enabled no)
				(sheetname "")
			)
			(fill
				(thermal_gap 0.5)
				(thermal_bridge_width 0.5)
				(island_removal_mode 0)
			)
			(polygon
				(pts
					(xy 38.543992 -293.878762) (xy 35.521392 -293.878762) (xy 35.521392 -290.983162) (xy 35.521392 -290.652962)
					(xy 38.543992 -290.652962) (xy 38.543992 -290.983162)
				)
			)
		)
	)
	(footprint ""
		(layer "F.Cu")
		(at 4.040124 -306.660042 -90)
		(property "Reference" "CN3"
			(at 0 0 270)
			(layer "F.SilkS")
			(hide yes)
			(effects
				(font
					(size 1.27 1.27)
				)
			)
		)
		(property "Value" "JWT-CON5-42-GP"
			(at -7.8105 2.9591 270)
			(unlocked yes)
			(layer "F.Fab")
			(hide yes)
			(effects
				(font
					(size 1.016 1.016)
					(thickness 0.1524)
				)
			)
		)
		(property "Device Type" "A2541WR0-1TX5PA-6T-0E"
			(at -7.8105 1.4351 270)
			(unlocked yes)
			(layer "F.Fab")
			(hide yes)
			(effects
				(font
					(size 1.016 1.016)
					(thickness 0.1524)
				)
			)
		)
		(duplicate_pad_numbers_are_jumpers no)
		(fp_line
			(start -6.604 10.287)
			(end 6.604 10.287)
			(stroke
				(width 0.1524)
				(type default)
			)
			(layer "F.SilkS")
		)
		(fp_line
			(start 6.604 10.287)
			(end 6.604 -0.9652)
			(stroke
				(width 0.1524)
				(type default)
			)
			(layer "F.SilkS")
		)
		(fp_line
			(start -6.604 -0.9652)
			(end -6.604 10.287)
			(stroke
				(width 0.1524)
				(type default)
			)
			(layer "F.SilkS")
		)
		(fp_line
			(start 6.604 -0.9652)
			(end -6.604 -0.9652)
			(stroke
				(width 0.1524)
				(type default)
			)
			(layer "F.SilkS")
		)
		(fp_line
			(start -6.731 -1.0922)
			(end -6.731 0.1778)
			(stroke
				(width 0.4064)
				(type default)
			)
			(layer "F.SilkS")
		)
		(fp_line
			(start -5.461 -1.0922)
			(end -6.731 -1.0922)
			(stroke
				(width 0.4064)
				(type default)
			)
			(layer "F.SilkS")
		)
		(fp_circle
			(center -5.08 0)
			(end -5.08 -1.0668)
			(stroke
				(width 0.3048)
				(type default)
			)
			(fill no)
			(layer "F.SilkS")
		)
		(fp_circle
			(center -2.54 0)
			(end -2.54 -1.0668)
			(stroke
				(width 0.3048)
				(type default)
			)
			(fill no)
			(layer "F.SilkS")
		)
		(fp_circle
			(center 0 0)
			(end 0 -1.0668)
			(stroke
				(width 0.3048)
				(type default)
			)
			(fill no)
			(layer "F.SilkS")
		)
		(fp_circle
			(center 2.54 0)
			(end 2.54 -1.0668)
			(stroke
				(width 0.3048)
				(type default)
			)
			(fill no)
			(layer "F.SilkS")
		)
		(fp_circle
			(center 5.08 0)
			(end 5.08 -1.0668)
			(stroke
				(width 0.3048)
				(type default)
			)
			(fill no)
			(layer "F.SilkS")
		)
		(fp_rect
			(start -6.35 10.033)
			(end 6.35 -0.3302)
			(stroke
				(width 0)
				(type default)
			)
			(fill no)
			(layer "F.CrtYd")
		)
		(fp_poly
			(pts
				(xy -6.35 -0.3302) (xy 6.858 -0.3302) (xy 6.858 -1.2192) (xy -6.858 -1.2192) (xy -6.858 10.541)
				(xy 6.858 10.541) (xy 6.858 -0.3175) (xy 6.35 -0.3175) (xy 6.35 10.033) (xy -6.35 10.033)
			)
			(stroke
				(width 0)
				(type default)
			)
			(fill no)
			(layer "F.CrtYd")
		)
		(fp_rect
			(start -6.858 10.541)
			(end 6.858 -1.2192)
			(stroke
				(width 0)
				(type default)
			)
			(fill no)
			(layer "F.Fab")
		)
		(pad "1" thru_hole circle
			(at -5.08 0 270)
			(size 1.4224 1.4224)
			(drill 1.016)
			(layers "*.Cu" "*.Mask")
			(remove_unused_layers no)
			(net "GND")
			(clearance 0.1524)
			(thermal_gap 0.1524)
		)
		(pad "2" thru_hole circle
			(at -2.54 0 270)
			(size 1.4224 1.4224)
			(drill 1.016)
			(layers "*.Cu" "*.Mask")
			(remove_unused_layers no)
			(net "P12V_FAN3")
			(clearance 0.1524)
			(thermal_gap 0.1524)
		)
		(pad "3" thru_hole circle
			(at 0 0 270)
			(size 1.4224 1.4224)
			(drill 1.016)
			(layers "*.Cu" "*.Mask")
			(remove_unused_layers no)
			(net "FAN_TACH6")
			(clearance 0.1524)
			(thermal_gap 0.1524)
		)
		(pad "4" thru_hole circle
			(at 2.54 0 270)
			(size 1.4224 1.4224)
			(drill 1.016)
			(layers "*.Cu" "*.Mask")
			(remove_unused_layers no)
			(net "PWM_OUT_FAN3_NET")
			(clearance 0.1524)
			(thermal_gap 0.1524)
		)
		(pad "5" thru_hole circle
			(at 5.08 0 270)
			(size 1.4224 1.4224)
			(drill 1.016)
			(layers "*.Cu" "*.Mask")
			(remove_unused_layers no)
			(net "FAN_TACH5")
			(clearance 0.1524)
			(thermal_gap 0.1524)
		)
	)
	(footprint ""
		(layer "F.Cu")
		(at 31.571692 -481.559362 180)
		(property "Reference" "TC18"
			(at 0 0 180)
			(layer "F.SilkS")
			(hide yes)
			(effects
				(font
					(size 1.27 1.27)
				)
			)
		)
		(property "Value" "ST15U25VDM-1-GP"
			(at 0 -9.6012 180)
			(unlocked yes)
			(layer "F.Fab")
			(hide yes)
			(effects
				(font
					(size 1.016 1.016)
					(thickness 0.1524)
				)
			)
		)
		(property "Device Type" "CT7343H79"
			(at 0 -11.1252 180)
			(unlocked yes)
			(layer "F.Fab")
			(hide yes)
			(effects
				(font
					(size 1.016 1.016)
					(thickness 0.1524)
				)
			)
		)
		(duplicate_pad_numbers_are_jumpers no)
		(fp_line
			(start 2.286 4.8768)
			(end -2.286 4.8768)
			(stroke
				(width 0.1524)
				(type default)
			)
			(layer "F.SilkS")
		)
		(fp_line
			(start 2.286 2.032)
			(end 2.286 4.8768)
			(stroke
				(width 0.1524)
				(type default)
			)
			(layer "F.SilkS")
		)
		(fp_line
			(start 2.286 -2.032)
			(end 2.286 -4.8768)
			(stroke
				(width 0.1524)
				(type default)
			)
			(layer "F.SilkS")
		)
		(fp_line
			(start 2.286 -4.8768)
			(end -2.286 -4.8768)
			(stroke
				(width 0.1524)
				(type default)
			)
			(layer "F.SilkS")
		)
		(fp_line
			(start 2.1082 -4.699)
			(end -2.1082 -4.699)
			(stroke
				(width 0.508)
				(type default)
			)
			(layer "F.SilkS")
		)
		(fp_line
			(start -2.286 4.8768)
			(end -2.286 2.032)
			(stroke
				(width 0.1524)
				(type default)
			)
			(layer "F.SilkS")
		)
		(fp_line
			(start -2.286 -4.8768)
			(end -2.286 -2.032)
			(stroke
				(width 0.1524)
				(type default)
			)
			(layer "F.SilkS")
		)
		(fp_rect
			(start -2.1463 3.6449)
			(end 2.1463 -3.6449)
			(stroke
				(width 0)
				(type default)
			)
			(fill no)
			(layer "F.CrtYd")
		)
		(fp_poly
			(pts
				(xy -2.54 4.953) (xy -2.54 4.2926) (xy -3.81 4.2926) (xy -3.81 -4.2926) (xy -2.54 -4.2926) (xy -2.54 -4.953)
				(xy 2.54 -4.953) (xy 2.54 -4.2926) (xy 3.81 -4.2926) (xy 3.81 -1.6256) (xy 2.1463 -1.6256) (xy 2.1463 -3.6449)
				(xy -2.1463 -3.6449) (xy -2.1463 3.6449) (xy 2.1463 3.6449) (xy 2.1463 -1.6129) (xy 3.81 -1.6129)
				(xy 3.81 4.2926) (xy 2.54 4.2926) (xy 2.54 4.953)
			)
			(stroke
				(width 0)
				(type default)
			)
			(fill no)
			(layer "F.CrtYd")
		)
		(fp_rect
			(start 2.54 4.2926)
			(end 3.81 -4.2926)
			(stroke
				(width 0)
				(type default)
			)
			(fill no)
			(layer "F.Fab")
		)
		(fp_rect
			(start -2.54 4.953)
			(end 2.54 -4.953)
			(stroke
				(width 0)
				(type default)
			)
			(fill no)
			(layer "F.Fab")
		)
		(fp_rect
			(start -3.81 4.2926)
			(end -2.54 -4.2926)
			(stroke
				(width 0)
				(type default)
			)
			(fill no)
			(layer "F.Fab")
		)
		(pad "1" smd rect
			(at 0 -3.1496 180)
			(size 2.413 2.286)
			(layers "F.Cu" "F.Mask" "F.Paste")
			(net "P12V")
		)
		(pad "2" smd rect
			(at 0 3.1496 180)
			(size 2.413 2.286)
			(layers "F.Cu" "F.Mask" "F.Paste")
			(net "GND")
		)
		(zone
			(layer "F.Cu")
			(hatch none 0.5)
			(connect_pads
				(clearance 0)
			)
			(min_thickness 0.25)
			(keepout
				(tracks allowed)
				(vias not_allowed)
				(pads allowed)
				(copperpour not_allowed)
				(footprints allowed)
			)
			(placement
				(enabled no)
				(sheetname "")
			)
			(fill
				(thermal_gap 0.5)
				(thermal_bridge_width 0.5)
				(island_removal_mode 0)
			)
			(polygon
				(pts
					(xy 30.060392 -479.870262) (xy 30.060392 -476.961962) (xy 33.082992 -476.961962) (xy 33.082992 -479.857562)
					(xy 33.082992 -480.187762) (xy 30.060392 -480.187762)
				)
			)
		)
		(zone
			(layer "F.Cu")
			(hatch none 0.5)
			(connect_pads
				(clearance 0)
			)
			(min_thickness 0.25)
			(keepout
				(tracks allowed)
				(vias not_allowed)
				(pads allowed)
				(copperpour not_allowed)
				(footprints allowed)
			)
			(placement
				(enabled no)
				(sheetname "")
			)
			(fill
				(thermal_gap 0.5)
				(thermal_bridge_width 0.5)
				(island_removal_mode 0)
			)
			(polygon
				(pts
					(xy 33.082992 -486.156762) (xy 30.060392 -486.156762) (xy 30.060392 -483.261162) (xy 30.060392 -482.930962)
					(xy 33.082992 -482.930962) (xy 33.082992 -483.261162)
				)
			)
		)
	)
	(footprint ""
		(layer "F.Cu")
		(at 21.6408 -290.322 -90)
		(property "Reference" "C44"
			(at 0 0 270)
			(layer "F.SilkS")
			(hide yes)
			(effects
				(font
					(size 1.27 1.27)
				)
			)
		)
		(property "Value" "SCD1U16V2KX-3GP"
			(at 1.1811 -2.7051 270)
			(unlocked yes)
			(layer "F.Fab")
			(hide yes)
			(effects
				(font
					(size 1.016 1.016)
					(thickness 0.1524)
				)
			)
		)
		(property "Device Type" "C402H22"
			(at 1.1811 -4.2291 270)
			(unlocked yes)
			(layer "F.Fab")
			(hide yes)
			(effects
				(font
					(size 1.016 1.016)
					(thickness 0.1524)
				)
			)
		)
		(duplicate_pad_numbers_are_jumpers no)
		(fp_rect
			(start -0.4318 0.9525)
			(end 0.4318 -0.9525)
			(stroke
				(width 0)
				(type default)
			)
			(fill no)
			(layer "F.CrtYd")
		)
		(fp_rect
			(start -0.4318 0.9525)
			(end 0.4318 -0.9525)
			(stroke
				(width 0)
				(type default)
			)
			(fill no)
			(layer "F.Fab")
		)
		(pad "1" smd custom
			(at 0 -0.4445 270)
			(size 0.1524 0.1524)
			(layers "F.Cu" "F.Mask" "F.Paste")
			(net "FAN_TACH4")
			(options
				(clearance outline)
				(anchor circle)
			)
			(primitives
				(gr_poly
					(pts
						(arc
							(start 0.3048 -0.2032)
							(mid 0.275042 -0.275042)
							(end 0.2032 -0.3048)
						)
						(arc
							(start -0.2032 -0.3048)
							(mid -0.275042 -0.275042)
							(end -0.3048 -0.2032)
						)
						(arc
							(start -0.3048 0.2032)
							(mid -0.275042 0.275042)
							(end -0.2032 0.3048)
						)
						(arc
							(start 0.2032 0.3048)
							(mid 0.275042 0.275042)
							(end 0.3048 0.2032)
						)
					)
					(width 0)
					(fill yes)
				)
			)
		)
		(pad "2" smd custom
			(at 0 0.4445 270)
			(size 0.1524 0.1524)
			(layers "F.Cu" "F.Mask" "F.Paste")
			(net "GND")
			(options
				(clearance outline)
				(anchor circle)
			)
			(primitives
				(gr_poly
					(pts
						(arc
							(start 0.3048 -0.2032)
							(mid 0.275042 -0.275042)
							(end 0.2032 -0.3048)
						)
						(arc
							(start -0.2032 -0.3048)
							(mid -0.275042 -0.275042)
							(end -0.3048 -0.2032)
						)
						(arc
							(start -0.3048 0.2032)
							(mid -0.275042 0.275042)
							(end -0.2032 0.3048)
						)
						(arc
							(start 0.2032 0.3048)
							(mid 0.275042 0.275042)
							(end 0.3048 0.2032)
						)
					)
					(width 0)
					(fill yes)
				)
			)
		)
	)
	(footprint ""
		(layer "F.Cu")
		(at 12.2428 -54.2036 90)
		(property "Reference" "R62"
			(at 0 0 90)
			(layer "F.SilkS")
			(hide yes)
			(effects
				(font
					(size 1.27 1.27)
				)
			)
		)
		(property "Value" "0R2J-2-GP"
			(at 0.064008 -3.993896 90)
			(unlocked yes)
			(layer "F.Fab")
			(hide yes)
			(effects
				(font
					(size 1.016 1.016)
					(thickness 0.1524)
				)
			)
		)
		(property "Device Type" "R402H16"
			(at 0.064008 -5.517896 90)
			(unlocked yes)
			(layer "F.Fab")
			(hide yes)
			(effects
				(font
					(size 1.016 1.016)
					(thickness 0.1524)
				)
			)
		)
		(duplicate_pad_numbers_are_jumpers no)
		(fp_line
			(start 0.508 -0.9398)
			(end -0.508 -0.9398)
			(stroke
				(width 0.1524)
				(type default)
			)
			(layer "F.SilkS")
		)
		(fp_line
			(start -0.508 -0.9398)
			(end -0.508 0.9398)
			(stroke
				(width 0.1524)
				(type default)
			)
			(layer "F.SilkS")
		)
		(fp_rect
			(start -0.508 0.9398)
			(end 0.508 -0.9398)
			(stroke
				(width 0)
				(type default)
			)
			(fill no)
			(layer "F.CrtYd")
		)
		(fp_rect
			(start -0.508 0.9398)
			(end 0.508 -0.9398)
			(stroke
				(width 0)
				(type default)
			)
			(fill no)
			(layer "F.Fab")
		)
		(pad "1" smd custom
			(at 0 -0.4445 90)
			(size 0.1397 0.1397)
			(layers "F.Cu" "F.Mask" "F.Paste")
			(net "SELF_TRAY_PRESENT_UPPER")
			(options
				(clearance outline)
				(anchor circle)
			)
			(primitives
				(gr_poly
					(pts
						(arc
							(start -0.1778 -0.2794)
							(mid -0.249642 -0.249642)
							(end -0.2794 -0.1778)
						)
						(arc
							(start -0.2794 0.1778)
							(mid -0.249642 0.249642)
							(end -0.1778 0.2794)
						)
						(arc
							(start 0.1778 0.2794)
							(mid 0.249642 0.249642)
							(end 0.2794 0.1778)
						)
						(arc
							(start 0.2794 -0.1778)
							(mid 0.249642 -0.249642)
							(end 0.1778 -0.2794)
						)
					)
					(width 0)
					(fill yes)
				)
			)
		)
		(pad "2" smd custom
			(at 0 0.4445 90)
			(size 0.1397 0.1397)
			(layers "F.Cu" "F.Mask" "F.Paste")
			(net "PEER_TRAY PRESENT_LOWER")
			(options
				(clearance outline)
				(anchor circle)
			)
			(primitives
				(gr_poly
					(pts
						(arc
							(start -0.1778 -0.2794)
							(mid -0.249642 -0.249642)
							(end -0.2794 -0.1778)
						)
						(arc
							(start -0.2794 0.1778)
							(mid -0.249642 0.249642)
							(end -0.1778 0.2794)
						)
						(arc
							(start 0.1778 0.2794)
							(mid 0.249642 0.249642)
							(end 0.2794 0.1778)
						)
						(arc
							(start 0.2794 -0.1778)
							(mid 0.249642 -0.249642)
							(end 0.1778 -0.2794)
						)
					)
					(width 0)
					(fill yes)
				)
			)
		)
	)
)
